# TIMECARD (Time Appliance Project (Time Card)) — schematic netlist excerpt (pin names and nets, part order shuffled) for the footprints in the layout excerpt that follows; sources: Cadence DE-HDL packaged netlist, KiCad conversion of R4006-B0001-02_R01.brd

R433  RESISTOR  33OHM 1%  pkg SMC_0402R_H016  page 25 : \1\ = UNNAMED_16_CONNHDR2X6FSSMT_I1_3 ; \2\ = FPGA_IO_1
R91  RESISTOR  33OHM 1%  pkg SMC_0402R_H016  page 21 : \1\ = ANALOG_TUNING_IN ; \2\ = SMA_ANALOG_TUNING_IN

(kicad_pcb
	(version 20260206)
	(generator "pcbnew")
	(generator_version "10.0")
	(general
		(thickness 1.6)
		(legacy_teardrops no)
	)
	(paper "A4")
	(title_block
		(title "timecard-production-celestica-r4006 — R4006-B0001-02_R01.brd")
		(comment 1 "Time Appliance Project (Time Card) / footprints 861-862 of 1113")
	)
	(layers
		(0 "F.Cu" signal "TOP")
		(4 "In1.Cu" signal "L02_GND1")
		(6 "In2.Cu" signal "L03_SIG1")
		(8 "In3.Cu" signal "L04_GND2")
		(10 "In4.Cu" signal "L05_VCC1")
		(12 "In5.Cu" signal "L06_VCC2")
		(14 "In6.Cu" signal "L07_GND3")
		(16 "In7.Cu" signal "L08_SIG2")
		(18 "In8.Cu" signal "L09_GND4")
		(2 "B.Cu" signal "BOTTOM")
		(9 "F.Adhes" user "F.Adhesive")
		(11 "B.Adhes" user "B.Adhesive")
		(13 "F.Paste" user "Package Geometry/Pastemask Top")
		(15 "B.Paste" user "Package Geometry/Pastemask Bottom")
		(5 "F.SilkS" user "Ref Des/Silkscreen Top")
		(7 "B.SilkS" user "Ref Des/Silkscreen Bottom")
		(1 "F.Mask" user "Board Geometry/Soldermask Top")
		(3 "B.Mask" user "Board Geometry/Soldermask Bottom")
		(17 "Dwgs.User" user "User.Drawings")
		(19 "Cmts.User" user "User.Comments")
		(21 "Eco1.User" user "User.Eco1")
		(23 "Eco2.User" user "User.Eco2")
		(25 "Edge.Cuts" user "Board Geometry/Outline")
		(27 "Margin" user)
		(31 "F.CrtYd" user "Package Geometry/Place Bound Top")
		(29 "B.CrtYd" user "Package Geometry/Place Bound Bottom")
		(35 "F.Fab" user "Ref Des/Assembly Top")
		(33 "B.Fab" user "Ref Des/Assembly Bottom")
	)
	(footprint ""
		(layer "B.Cu")
		(at 151.892 -42.037 90)
		(property "Reference" "R433"
			(at -8.42137 0.635 0)
			(unlocked yes)
			(layer "B.SilkS")
			(effects
				(font
					(size 0.7874 0.5842)
					(thickness 0.1524)
				)
				(justify mirror)
			)
		)
		(property "Value" "VAL*"
			(at -0.02032 2.13233 90)
			(unlocked yes)
			(layer "B.Fab")
			(hide yes)
			(effects
				(font
					(size 0.7874 0.5842)
					(thickness 0.1524)
				)
				(justify mirror)
			)
		)
		(property "Tolerance" "TOL*"
			(at -0.044704 3.05435 90)
			(unlocked yes)
			(layer "Cmts.User")
			(hide yes)
			(effects
				(font
					(size 0.7874 0.5842)
					(thickness 0.1524)
				)
				(justify mirror)
			)
		)
		(property "User Part Number" "PARTNUM*"
			(at -0.02032 4.024884 90)
			(unlocked yes)
			(layer "Cmts.User")
			(hide yes)
			(effects
				(font
					(size 0.7874 0.5842)
					(thickness 0.1524)
				)
				(justify mirror)
			)
		)
		(property "Device Type" "RESISTOR-G155-133R0-01,33OHM,1%"
			(at -0.008382 1.210564 90)
			(unlocked yes)
			(layer "B.Fab")
			(hide yes)
			(effects
				(font
					(size 0.7874 0.5842)
					(thickness 0.1524)
				)
				(justify mirror)
			)
		)
		(duplicate_pad_numbers_are_jumpers no)
		(fp_line
			(start 1.143 -0.5588)
			(end 1.143 0.5588)
			(stroke
				(width 0.1)
				(type default)
			)
			(layer "B.SilkS")
		)
		(fp_line
			(start -1.143 -0.5588)
			(end 1.143 -0.5588)
			(stroke
				(width 0.1)
				(type default)
			)
			(layer "B.SilkS")
		)
		(fp_line
			(start 1.143 0.5588)
			(end -1.143 0.5588)
			(stroke
				(width 0.1)
				(type default)
			)
			(layer "B.SilkS")
		)
		(fp_line
			(start -1.143 0.5588)
			(end -1.143 -0.5588)
			(stroke
				(width 0.1)
				(type default)
			)
			(layer "B.SilkS")
		)
		(fp_poly
			(pts
				(xy 1.143 0.5588) (xy -1.143 0.5588) (xy -1.143 -0.5588) (xy 1.143 -0.5588)
			)
			(stroke
				(width 0)
				(type default)
			)
			(fill no)
			(layer "B.CrtYd")
		)
		(fp_line
			(start 0.508 -0.3048)
			(end 0.508 0.3048)
			(stroke
				(width 0.1)
				(type default)
			)
			(layer "B.Fab")
		)
		(fp_line
			(start -0.508 -0.3048)
			(end 0.508 -0.3048)
			(stroke
				(width 0.1)
				(type default)
			)
			(layer "B.Fab")
		)
		(fp_line
			(start 0.508 0.3048)
			(end -0.508 0.3048)
			(stroke
				(width 0.1)
				(type default)
			)
			(layer "B.Fab")
		)
		(fp_line
			(start -0.508 0.3048)
			(end -0.508 -0.3048)
			(stroke
				(width 0.1)
				(type default)
			)
			(layer "B.Fab")
		)
		(pad "1" smd rect
			(at 0.5334 0 270)
			(size 0.7112 0.6096)
			(layers "B.Cu" "B.Mask" "B.Paste")
			(net "UNNAMED_16_CONNHDR2X6FSSMT_I1_3")
		)
		(pad "2" smd rect
			(at -0.5334 0 270)
			(size 0.7112 0.6096)
			(layers "B.Cu" "B.Mask" "B.Paste")
			(net "FPGA_IO_1")
		)
		(zone
			(layer "B.Cu")
			(hatch none 0.5)
			(connect_pads
				(clearance 0)
			)
			(min_thickness 0.25)
			(keepout
				(tracks allowed)
				(vias not_allowed)
				(pads allowed)
				(copperpour not_allowed)
				(footprints allowed)
			)
			(placement
				(enabled no)
				(sheetname "")
			)
			(fill
				(thermal_gap 0.5)
				(thermal_bridge_width 0.5)
				(island_removal_mode 0)
			)
			(polygon
				(pts
					(xy 152.1968 -42.1132) (xy 151.5872 -42.1132) (xy 151.5872 -41.9608) (xy 152.1968 -41.9608)
				)
			)
		)
		(zone
			(layer "B.Cu")
			(hatch none 0.5)
			(connect_pads
				(clearance 0)
			)
			(min_thickness 0.25)
			(keepout
				(tracks not_allowed)
				(vias allowed)
				(pads allowed)
				(copperpour not_allowed)
				(footprints allowed)
			)
			(placement
				(enabled no)
				(sheetname "")
			)
			(fill
				(thermal_gap 0.5)
				(thermal_bridge_width 0.5)
				(island_removal_mode 0)
			)
			(polygon
				(pts
					(xy 152.1968 -42.1132) (xy 151.5872 -42.1132) (xy 151.5872 -41.9608) (xy 152.1968 -41.9608)
				)
			)
		)
	)
	(footprint ""
		(layer "B.Cu")
		(at 23.0632 -71.374 90)
		(property "Reference" "R91"
			(at -1.905 1.02743 270)
			(unlocked yes)
			(layer "B.SilkS")
			(effects
				(font
					(size 0.7874 0.5842)
					(thickness 0.1524)
				)
				(justify mirror)
			)
		)
		(property "Value" "VAL*"
			(at -0.02032 2.13233 90)
			(unlocked yes)
			(layer "B.Fab")
			(hide yes)
			(effects
				(font
					(size 0.7874 0.5842)
					(thickness 0.1524)
				)
				(justify mirror)
			)
		)
		(property "Device Type" "RESISTOR-G155-133R0-01,33OHM,1%"
			(at -0.008382 1.210564 90)
			(unlocked yes)
			(layer "B.Fab")
			(hide yes)
			(effects
				(font
					(size 0.7874 0.5842)
					(thickness 0.1524)
				)
				(justify mirror)
			)
		)
		(property "User Part Number" "PARTNUM*"
			(at -0.02032 4.024884 90)
			(unlocked yes)
			(layer "Cmts.User")
			(hide yes)
			(effects
				(font
					(size 0.7874 0.5842)
					(thickness 0.1524)
				)
				(justify mirror)
			)
		)
		(property "Tolerance" "TOL*"
			(at -0.044704 3.05435 90)
			(unlocked yes)
			(layer "Cmts.User")
			(hide yes)
			(effects
				(font
					(size 0.7874 0.5842)
					(thickness 0.1524)
				)
				(justify mirror)
			)
		)
		(duplicate_pad_numbers_are_jumpers no)
		(fp_line
			(start 1.143 -0.5588)
			(end 1.143 0.5588)
			(stroke
				(width 0.1)
				(type default)
			)
			(layer "B.SilkS")
		)
		(fp_line
			(start -1.143 -0.5588)
			(end 1.143 -0.5588)
			(stroke
				(width 0.1)
				(type default)
			)
			(layer "B.SilkS")
		)
		(fp_line
			(start 1.143 0.5588)
			(end -1.143 0.5588)
			(stroke
				(width 0.1)
				(type default)
			)
			(layer "B.SilkS")
		)
		(fp_line
			(start -1.143 0.5588)
			(end -1.143 -0.5588)
			(stroke
				(width 0.1)
				(type default)
			)
			(layer "B.SilkS")
		)
		(fp_rect
			(start 1.143 0.5588)
			(end -1.143 -0.5588)
			(stroke
				(width 0)
				(type default)
			)
			(fill no)
			(layer "B.CrtYd")
		)
		(fp_line
			(start 0.508 -0.3048)
			(end 0.508 0.3048)
			(stroke
				(width 0.1)
				(type default)
			)
			(layer "B.Fab")
		)
		(fp_line
			(start -0.508 -0.3048)
			(end 0.508 -0.3048)
			(stroke
				(width 0.1)
				(type default)
			)
			(layer "B.Fab")
		)
		(fp_line
			(start 0.508 0.3048)
			(end -0.508 0.3048)
			(stroke
				(width 0.1)
				(type default)
			)
			(layer "B.Fab")
		)
		(fp_line
			(start -0.508 0.3048)
			(end -0.508 -0.3048)
			(stroke
				(width 0.1)
				(type default)
			)
			(layer "B.Fab")
		)
		(pad "1" smd rect
			(at 0.5334 0 270)
			(size 0.7112 0.6096)
			(layers "B.Cu" "B.Mask" "B.Paste")
			(net "ANALOG_TUNING_IN")
		)
		(pad "2" smd rect
			(at -0.5334 0 270)
			(size 0.7112 0.6096)
			(layers "B.Cu" "B.Mask" "B.Paste")
			(net "SMA_ANALOG_TUNING_IN")
		)
		(zone
			(layer "B.Cu")
			(hatch none 0.5)
			(connect_pads
				(clearance 0)
			)
			(min_thickness 0.25)
			(keepout
				(tracks not_allowed)
				(vias allowed)
				(pads allowed)
				(copperpour not_allowed)
				(footprints allowed)
			)
			(placement
				(enabled no)
				(sheetname "")
			)
			(fill
				(thermal_gap 0.5)
				(thermal_bridge_width 0.5)
				(island_removal_mode 0)
			)
			(polygon
				(pts
					(xy 23.368 -71.4502) (xy 22.7584 -71.4502) (xy 22.7584 -71.2978) (xy 23.368 -71.2978)
				)
			)
		)
		(zone
			(layer "B.Cu")
			(hatch none 0.5)
			(connect_pads
				(clearance 0)
			)
			(min_thickness 0.25)
			(keepout
				(tracks allowed)
				(vias not_allowed)
				(pads allowed)
				(copperpour not_allowed)
				(footprints allowed)
			)
			(placement
				(enabled no)
				(sheetname "")
			)
			(fill
				(thermal_gap 0.5)
				(thermal_bridge_width 0.5)
				(island_removal_mode 0)
			)
			(polygon
				(pts
					(xy 23.368 -71.4502) (xy 22.7584 -71.4502) (xy 22.7584 -71.2978) (xy 23.368 -71.2978)
				)
			)
		)
	)
)
